# TIMECARD (Time Appliance Project (Time Card)) — schematic netlist excerpt (pin names and nets, part order shuffled) for the footprints in the layout excerpt that follows; sources: Cadence DE-HDL packaged netlist, KiCad conversion of R4006-B0001-02_R01.brd

R348  RESISTOR  33OHM 1%  pkg SMC_0402R_H016  page 11 : \1\ = FPGA_D03 ; \2\ = FPGA_FLASH_DQ3
R394  RESISTOR  33OHM 1%  pkg SMC_0402R_H016  page 26 : \1\ = SMA4_LED_BLUE_N ; \2\ = UNNAMED_14_LED4PV14_I268_1

(kicad_pcb
	(version 20260206)
	(generator "pcbnew")
	(generator_version "10.0")
	(general
		(thickness 1.6)
		(legacy_teardrops no)
	)
	(paper "A4")
	(title_block
		(title "timecard-production-celestica-r4006 — R4006-B0001-02_R01.brd")
		(comment 1 "Time Appliance Project (Time Card) / footprints 153-154 of 1113")
	)
	(layers
		(0 "F.Cu" signal "TOP")
		(4 "In1.Cu" signal "L02_GND1")
		(6 "In2.Cu" signal "L03_SIG1")
		(8 "In3.Cu" signal "L04_GND2")
		(10 "In4.Cu" signal "L05_VCC1")
		(12 "In5.Cu" signal "L06_VCC2")
		(14 "In6.Cu" signal "L07_GND3")
		(16 "In7.Cu" signal "L08_SIG2")
		(18 "In8.Cu" signal "L09_GND4")
		(2 "B.Cu" signal "BOTTOM")
		(9 "F.Adhes" user "F.Adhesive")
		(11 "B.Adhes" user "B.Adhesive")
		(13 "F.Paste" user "Package Geometry/Pastemask Top")
		(15 "B.Paste" user "Package Geometry/Pastemask Bottom")
		(5 "F.SilkS" user "Ref Des/Silkscreen Top")
		(7 "B.SilkS" user "Ref Des/Silkscreen Bottom")
		(1 "F.Mask" user "Board Geometry/Soldermask Top")
		(3 "B.Mask" user "Board Geometry/Soldermask Bottom")
		(17 "Dwgs.User" user "User.Drawings")
		(19 "Cmts.User" user "User.Comments")
		(21 "Eco1.User" user "User.Eco1")
		(23 "Eco2.User" user "User.Eco2")
		(25 "Edge.Cuts" user "Board Geometry/Outline")
		(27 "Margin" user)
		(31 "F.CrtYd" user "Package Geometry/Place Bound Top")
		(29 "B.CrtYd" user "Package Geometry/Place Bound Bottom")
		(35 "F.Fab" user "Ref Des/Assembly Top")
		(33 "B.Fab" user "Ref Des/Assembly Bottom")
	)
	(footprint ""
		(layer "F.Cu")
		(at 19.468338 -44.45 180)
		(property "Reference" "R394"
			(at -3.518662 -0.16637 0)
			(unlocked yes)
			(layer "F.SilkS")
			(effects
				(font
					(size 0.7874 0.5842)
					(thickness 0.1524)
				)
			)
		)
		(property "Value" "VAL*"
			(at 0.02032 2.13233 180)
			(unlocked yes)
			(layer "F.Fab")
			(hide yes)
			(effects
				(font
					(size 0.7874 0.5842)
					(thickness 0.1524)
				)
			)
		)
		(property "Tolerance" "TOL*"
			(at 0.044704 3.05435 180)
			(unlocked yes)
			(layer "Cmts.User")
			(hide yes)
			(effects
				(font
					(size 0.7874 0.5842)
					(thickness 0.1524)
				)
			)
		)
		(property "User Part Number" "PARTNUM*"
			(at 0.02032 4.024884 180)
			(unlocked yes)
			(layer "Cmts.User")
			(hide yes)
			(effects
				(font
					(size 0.7874 0.5842)
					(thickness 0.1524)
				)
			)
		)
		(property "Device Type" "RESISTOR-G155-133R0-01,33OHM,1%"
			(at 0.008382 1.210564 180)
			(unlocked yes)
			(layer "F.Fab")
			(hide yes)
			(effects
				(font
					(size 0.7874 0.5842)
					(thickness 0.1524)
				)
			)
		)
		(duplicate_pad_numbers_are_jumpers no)
		(fp_line
			(start 1.143 0.5588)
			(end 1.143 -0.5588)
			(stroke
				(width 0.1)
				(type default)
			)
			(layer "F.SilkS")
		)
		(fp_line
			(start 1.143 -0.5588)
			(end -1.143 -0.5588)
			(stroke
				(width 0.1)
				(type default)
			)
			(layer "F.SilkS")
		)
		(fp_line
			(start -1.143 0.5588)
			(end 1.143 0.5588)
			(stroke
				(width 0.1)
				(type default)
			)
			(layer "F.SilkS")
		)
		(fp_line
			(start -1.143 -0.5588)
			(end -1.143 0.5588)
			(stroke
				(width 0.1)
				(type default)
			)
			(layer "F.SilkS")
		)
		(fp_rect
			(start -1.143 -0.5588)
			(end 1.143 0.5588)
			(stroke
				(width 0)
				(type default)
			)
			(fill no)
			(layer "F.CrtYd")
		)
		(fp_line
			(start 0.508 0.3048)
			(end 0.508 -0.3048)
			(stroke
				(width 0.1)
				(type default)
			)
			(layer "F.Fab")
		)
		(fp_line
			(start 0.508 -0.3048)
			(end -0.508 -0.3048)
			(stroke
				(width 0.1)
				(type default)
			)
			(layer "F.Fab")
		)
		(fp_line
			(start -0.508 0.3048)
			(end 0.508 0.3048)
			(stroke
				(width 0.1)
				(type default)
			)
			(layer "F.Fab")
		)
		(fp_line
			(start -0.508 -0.3048)
			(end -0.508 0.3048)
			(stroke
				(width 0.1)
				(type default)
			)
			(layer "F.Fab")
		)
		(pad "1" smd rect
			(at -0.5334 0 180)
			(size 0.7112 0.6096)
			(layers "F.Cu" "F.Mask" "F.Paste")
			(net "SMA4_LED_BLUE_N")
		)
		(pad "2" smd rect
			(at 0.5334 0 180)
			(size 0.7112 0.6096)
			(layers "F.Cu" "F.Mask" "F.Paste")
			(net "UNNAMED_14_LED4PV14_I268_1")
		)
		(zone
			(layer "F.Cu")
			(hatch none 0.5)
			(connect_pads
				(clearance 0)
			)
			(min_thickness 0.25)
			(keepout
				(tracks allowed)
				(vias not_allowed)
				(pads allowed)
				(copperpour not_allowed)
				(footprints allowed)
			)
			(placement
				(enabled no)
				(sheetname "")
			)
			(fill
				(thermal_gap 0.5)
				(thermal_bridge_width 0.5)
				(island_removal_mode 0)
			)
			(polygon
				(pts
					(xy 19.544538 -44.1452) (xy 19.544538 -44.7548) (xy 19.392138 -44.7548) (xy 19.392138 -44.1452)
				)
			)
		)
		(zone
			(layer "F.Cu")
			(hatch none 0.5)
			(connect_pads
				(clearance 0)
			)
			(min_thickness 0.25)
			(keepout
				(tracks not_allowed)
				(vias allowed)
				(pads allowed)
				(copperpour not_allowed)
				(footprints allowed)
			)
			(placement
				(enabled no)
				(sheetname "")
			)
			(fill
				(thermal_gap 0.5)
				(thermal_bridge_width 0.5)
				(island_removal_mode 0)
			)
			(polygon
				(pts
					(xy 19.544538 -44.1452) (xy 19.544538 -44.7548) (xy 19.392138 -44.7548) (xy 19.392138 -44.1452)
				)
			)
		)
	)
	(footprint ""
		(layer "F.Cu")
		(at 117.348 -61.976 90)
		(property "Reference" "R348"
			(at 3.302 0.80137 90)
			(unlocked yes)
			(layer "F.SilkS")
			(effects
				(font
					(size 0.7874 0.5842)
					(thickness 0.1524)
				)
			)
		)
		(property "Value" "VAL*"
			(at 0.02032 2.13233 90)
			(unlocked yes)
			(layer "F.Fab")
			(hide yes)
			(effects
				(font
					(size 0.7874 0.5842)
					(thickness 0.1524)
				)
			)
		)
		(property "Tolerance" "TOL*"
			(at 0.044704 3.05435 90)
			(unlocked yes)
			(layer "Cmts.User")
			(hide yes)
			(effects
				(font
					(size 0.7874 0.5842)
					(thickness 0.1524)
				)
			)
		)
		(property "User Part Number" "PARTNUM*"
			(at 0.02032 4.024884 90)
			(unlocked yes)
			(layer "Cmts.User")
			(hide yes)
			(effects
				(font
					(size 0.7874 0.5842)
					(thickness 0.1524)
				)
			)
		)
		(property "Device Type" "RESISTOR-G155-133R0-01,33OHM,1%"
			(at 0.008382 1.210564 90)
			(unlocked yes)
			(layer "F.Fab")
			(hide yes)
			(effects
				(font
					(size 0.7874 0.5842)
					(thickness 0.1524)
				)
			)
		)
		(duplicate_pad_numbers_are_jumpers no)
		(fp_line
			(start 1.143 -0.5588)
			(end -1.143 -0.5588)
			(stroke
				(width 0.1)
				(type default)
			)
			(layer "F.SilkS")
		)
		(fp_line
			(start -1.143 -0.5588)
			(end -1.143 0.5588)
			(stroke
				(width 0.1)
				(type default)
			)
			(layer "F.SilkS")
		)
		(fp_line
			(start 1.143 0.5588)
			(end 1.143 -0.5588)
			(stroke
				(width 0.1)
				(type default)
			)
			(layer "F.SilkS")
		)
		(fp_line
			(start -1.143 0.5588)
			(end 1.143 0.5588)
			(stroke
				(width 0.1)
				(type default)
			)
			(layer "F.SilkS")
		)
		(fp_poly
			(pts
				(xy -1.143 0.5588) (xy 1.143 0.5588) (xy 1.143 -0.5588) (xy -1.143 -0.5588)
			)
			(stroke
				(width 0)
				(type default)
			)
			(fill no)
			(layer "F.CrtYd")
		)
		(fp_line
			(start 0.508 -0.3048)
			(end -0.508 -0.3048)
			(stroke
				(width 0.1)
				(type default)
			)
			(layer "F.Fab")
		)
		(fp_line
			(start -0.508 -0.3048)
			(end -0.508 0.3048)
			(stroke
				(width 0.1)
				(type default)
			)
			(layer "F.Fab")
		)
		(fp_line
			(start 0.508 0.3048)
			(end 0.508 -0.3048)
			(stroke
				(width 0.1)
				(type default)
			)
			(layer "F.Fab")
		)
		(fp_line
			(start -0.508 0.3048)
			(end 0.508 0.3048)
			(stroke
				(width 0.1)
				(type default)
			)
			(layer "F.Fab")
		)
		(pad "1" smd rect
			(at -0.5334 0 90)
			(size 0.7112 0.6096)
			(layers "F.Cu" "F.Mask" "F.Paste")
			(net "FPGA_D03")
		)
		(pad "2" smd rect
			(at 0.5334 0 90)
			(size 0.7112 0.6096)
			(layers "F.Cu" "F.Mask" "F.Paste")
			(net "FPGA_FLASH_DQ3")
		)
		(zone
			(layer "F.Cu")
			(hatch none 0.5)
			(connect_pads
				(clearance 0)
			)
			(min_thickness 0.25)
			(keepout
				(tracks not_allowed)
				(vias allowed)
				(pads allowed)
				(copperpour not_allowed)
				(footprints allowed)
			)
			(placement
				(enabled no)
				(sheetname "")
			)
			(fill
				(thermal_gap 0.5)
				(thermal_bridge_width 0.5)
				(island_removal_mode 0)
			)
			(polygon
				(pts
					(xy 117.6528 -61.8998) (xy 117.6528 -62.0522) (xy 117.0432 -62.0522) (xy 117.0432 -61.8998)
				)
			)
		)
		(zone
			(layer "F.Cu")
			(hatch none 0.5)
			(connect_pads
				(clearance 0)
			)
			(min_thickness 0.25)
			(keepout
				(tracks allowed)
				(vias not_allowed)
				(pads allowed)
				(copperpour not_allowed)
				(footprints allowed)
			)
			(placement
				(enabled no)
				(sheetname "")
			)
			(fill
				(thermal_gap 0.5)
				(thermal_bridge_width 0.5)
				(island_removal_mode 0)
			)
			(polygon
				(pts
					(xy 117.6528 -61.8998) (xy 117.6528 -62.0522) (xy 117.0432 -62.0522) (xy 117.0432 -61.8998)
				)
			)
		)
	)
)
